(kicad_pcb
	(version 20260206)
	(generator "pcbnew")
	(generator_version "10.0")
	(general
		(thickness 1.6)
		(legacy_teardrops no)
	)
	(paper "A4")
	(title_block
		(title "v1-chassis-manager — T6M_CM_d_v01_1031_1645.brd")
		(comment 1 "Open CloudServer (Microsoft) / footprints 1549-1556 of 2512")
	)
	(layers
		(0 "F.Cu" signal "TOP")
		(4 "In1.Cu" signal "GND1")
		(6 "In2.Cu" signal "IN1")
		(8 "In3.Cu" signal "VCC1")
		(10 "In4.Cu" signal "VCC2")
		(12 "In5.Cu" signal "GND2")
		(14 "In6.Cu" signal "IN2")
		(16 "In7.Cu" signal "IN3")
		(18 "In8.Cu" signal "GND3")
		(2 "B.Cu" signal "BOTTOM")
		(9 "F.Adhes" user "F.Adhesive")
		(11 "B.Adhes" user "B.Adhesive")
		(13 "F.Paste" user "Package Geometry/Pastemask Top")
		(15 "B.Paste" user "Package Geometry/Pastemask Bottom")
		(5 "F.SilkS" user "Ref Des/Silkscreen Top")
		(7 "B.SilkS" user "Ref Des/Silkscreen Bottom")
		(1 "F.Mask" user "Board Geometry/Soldermask Top")
		(3 "B.Mask" user "Board Geometry/Soldermask Bottom")
		(17 "Dwgs.User" user "User.Drawings")
		(19 "Cmts.User" user "User.Comments")
		(21 "Eco1.User" user "User.Eco1")
		(23 "Eco2.User" user "User.Eco2")
		(25 "Edge.Cuts" user "Board Geometry/Outline")
		(27 "Margin" user)
		(31 "F.CrtYd" user "Package Geometry/Place Bound Top")
		(29 "B.CrtYd" user "Package Geometry/Place Bound Bottom")
		(35 "F.Fab" user "Ref Des/Assembly Top")
		(33 "B.Fab" user "Ref Des/Assembly Bottom")
	)
	(footprint ""
		(layer "F.Cu")
		(at 90.063066 -100.479606 180)
		(property "Reference" "U5"
			(at -5.448046 4.63804 0)
			(unlocked yes)
			(layer "F.SilkS")
			(effects
				(font
					(size 0.7874 0.5842)
					(thickness 0.1524)
				)
				(justify left)
			)
		)
		(property "Value" ""
			(at 0 0 180)
			(layer "F.Fab")
			(effects
				(font
					(size 1.27 1.27)
				)
			)
		)
		(duplicate_pad_numbers_are_jumpers no)
		(fp_line
			(start 4.76504 5.350002)
			(end -4.76504 5.350002)
			(stroke
				(width 0.1524)
				(type default)
			)
			(layer "F.SilkS")
		)
		(fp_line
			(start 4.76504 -5.350002)
			(end 4.76504 5.350002)
			(stroke
				(width 0.1524)
				(type default)
			)
			(layer "F.SilkS")
		)
		(fp_line
			(start -4.76504 5.350002)
			(end -4.76504 1.999996)
			(stroke
				(width 0.1524)
				(type default)
			)
			(layer "F.SilkS")
		)
		(fp_line
			(start -4.76504 1.999996)
			(end -8.465058 1.999996)
			(stroke
				(width 0.1524)
				(type default)
			)
			(layer "F.SilkS")
		)
		(fp_line
			(start -4.76504 -1.999996)
			(end -4.76504 -5.350002)
			(stroke
				(width 0.1524)
				(type default)
			)
			(layer "F.SilkS")
		)
		(fp_line
			(start -4.76504 -5.350002)
			(end 4.76504 -5.350002)
			(stroke
				(width 0.1524)
				(type default)
			)
			(layer "F.SilkS")
		)
		(fp_line
			(start -8.465058 1.999996)
			(end -8.465058 -1.999996)
			(stroke
				(width 0.1524)
				(type default)
			)
			(layer "F.SilkS")
		)
		(fp_line
			(start -8.465058 -1.999996)
			(end -4.76504 -1.999996)
			(stroke
				(width 0.1524)
				(type default)
			)
			(layer "F.SilkS")
		)
		(fp_poly
			(pts
				(xy 4.908296 -2.242058) (xy 5.924296 -2.750058) (xy 5.924296 -1.734058)
			)
			(stroke
				(width 0)
				(type default)
			)
			(fill yes)
			(layer "F.SilkS")
		)
		(fp_poly
			(pts
				(xy -4.76504 -5.350002) (xy 4.76504 -5.350002) (xy 4.76504 5.350002) (xy -4.76504 5.350002) (xy -4.76504 1.999996)
				(xy -8.465058 1.999996) (xy -8.465058 -1.999996) (xy -4.76504 -1.999996)
			)
			(stroke
				(width 0)
				(type default)
			)
			(fill no)
			(layer "F.CrtYd")
		)
		(fp_line
			(start 4.76504 5.350002)
			(end -4.76504 5.350002)
			(stroke
				(width 0.1)
				(type default)
			)
			(layer "F.Fab")
		)
		(fp_line
			(start 4.76504 -5.350002)
			(end 4.76504 5.350002)
			(stroke
				(width 0.1)
				(type default)
			)
			(layer "F.Fab")
		)
		(fp_line
			(start -4.76504 5.350002)
			(end -4.76504 1.999996)
			(stroke
				(width 0.1)
				(type default)
			)
			(layer "F.Fab")
		)
		(fp_line
			(start -4.76504 1.999996)
			(end -8.465058 1.999996)
			(stroke
				(width 0.1)
				(type default)
			)
			(layer "F.Fab")
		)
		(fp_line
			(start -4.76504 -1.999996)
			(end -4.76504 -5.350002)
			(stroke
				(width 0.1)
				(type default)
			)
			(layer "F.Fab")
		)
		(fp_line
			(start -4.76504 -5.350002)
			(end 4.76504 -5.350002)
			(stroke
				(width 0.1)
				(type default)
			)
			(layer "F.Fab")
		)
		(fp_line
			(start -8.465058 1.999996)
			(end -8.465058 -1.999996)
			(stroke
				(width 0.1)
				(type default)
			)
			(layer "F.Fab")
		)
		(fp_line
			(start -8.465058 -1.999996)
			(end -4.76504 -1.999996)
			(stroke
				(width 0.1)
				(type default)
			)
			(layer "F.Fab")
		)
		(fp_text user "8"
			(at 5.639054 5.441188 0)
			(unlocked yes)
			(layer "F.SilkS")
			(effects
				(font
					(size 0.635 0.4064)
					(thickness 0.1524)
				)
				(justify left)
			)
		)
		(fp_text user "1"
			(at 5.26669 -5.071364 0)
			(unlocked yes)
			(layer "F.SilkS")
			(effects
				(font
					(size 0.635 0.4064)
					(thickness 0.1524)
				)
				(justify left)
			)
		)
		(fp_text user "5"
			(at -3.871214 6.049518 0)
			(unlocked yes)
			(layer "F.SilkS")
			(effects
				(font
					(size 0.7874 0.5842)
					(thickness 0.1524)
				)
				(justify left)
			)
		)
		(fp_text user "4"
			(at -5.077968 -4.186936 0)
			(unlocked yes)
			(layer "F.SilkS")
			(effects
				(font
					(size 0.635 0.4064)
					(thickness 0.1524)
				)
				(justify left)
			)
		)
		(pad "1" smd rect
			(at 1.905 -3.379978 180)
			(size 0.6604 1.9304)
			(layers "F.Cu" "F.Mask" "F.Paste")
			(net "SPI_CPU_NODE1_CS0_L")
		)
		(pad "2" smd rect
			(at 0.635 -3.379978 180)
			(size 0.6604 1.9304)
			(layers "F.Cu" "F.Mask" "F.Paste")
			(net "SPI_CPU_NODE1_MISO_R")
		)
		(pad "3" smd rect
			(at -0.635 -3.379978 180)
			(size 0.6604 1.9304)
			(layers "F.Cu" "F.Mask" "F.Paste")
			(net "SPI_CPU_NODE1_WP_L")
		)
		(pad "4" smd rect
			(at -1.905 -3.379978 180)
			(size 0.6604 1.9304)
			(layers "F.Cu" "F.Mask" "F.Paste")
			(net "GND")
		)
		(pad "5" smd rect
			(at -1.905 3.379978 180)
			(size 0.6604 1.9304)
			(layers "F.Cu" "F.Mask" "F.Paste")
			(net "SPI_CPU_NODE1_MOSI")
		)
		(pad "6" smd rect
			(at -0.635 3.379978 180)
			(size 0.6604 1.9304)
			(layers "F.Cu" "F.Mask" "F.Paste")
			(net "SPI_CPU_NODE1_SCLK")
		)
		(pad "7" smd rect
			(at 0.635 3.379978 180)
			(size 0.6604 1.9304)
			(layers "F.Cu" "F.Mask" "F.Paste")
			(net "SPI_CPU_NODE1_HOLD_L")
		)
		(pad "8" smd rect
			(at 1.905 3.379978 180)
			(size 0.6604 1.9304)
			(layers "F.Cu" "F.Mask" "F.Paste")
			(net "P3V3_NODE1")
		)
	)
	(footprint ""
		(layer "F.Cu")
		(at 165.34638 -161.37001 90)
		(property "Reference" "R587"
			(at -8.06577 17.513554 90)
			(unlocked yes)
			(layer "F.SilkS")
			(effects
				(font
					(size 0.7874 0.5842)
					(thickness 0.1524)
				)
				(justify left)
			)
		)
		(property "Value" ""
			(at 0 0 90)
			(layer "F.Fab")
			(effects
				(font
					(size 1.27 1.27)
				)
			)
		)
		(duplicate_pad_numbers_are_jumpers no)
		(fp_line
			(start 0.7874 -0.4064)
			(end 0.7874 0.4064)
			(stroke
				(width 0.1524)
				(type default)
			)
			(layer "F.SilkS")
		)
		(fp_line
			(start -0.7874 -0.4064)
			(end 0.7874 -0.4064)
			(stroke
				(width 0.1524)
				(type default)
			)
			(layer "F.SilkS")
		)
		(fp_line
			(start 0.7874 0.4064)
			(end -0.7874 0.4064)
			(stroke
				(width 0.1524)
				(type default)
			)
			(layer "F.SilkS")
		)
		(fp_line
			(start -0.7874 0.4064)
			(end -0.7874 -0.4064)
			(stroke
				(width 0.1524)
				(type default)
			)
			(layer "F.SilkS")
		)
		(fp_poly
			(pts
				(xy -0.508 0.2794) (xy -0.508 0.2286) (xy -0.635 0.2286) (xy -0.635 -0.254) (xy -0.5334 -0.254)
				(xy -0.5334 -0.2794) (xy 0.5334 -0.2794) (xy 0.5334 -0.254) (xy 0.635 -0.254) (xy 0.635 0.254) (xy 0.5334 0.254)
				(xy 0.5334 0.2794)
			)
			(stroke
				(width 0)
				(type default)
			)
			(fill no)
			(layer "F.CrtYd")
		)
		(pad "1" smd rect
			(at 0.40005 0 90)
			(size 0.4572 0.508)
			(layers "F.Cu" "F.Mask" "F.Paste")
			(net "GND")
		)
		(pad "2" smd rect
			(at -0.40005 0 90)
			(size 0.4572 0.508)
			(layers "F.Cu" "F.Mask" "F.Paste")
			(net "LAN2_NC_SI_CRS_DV")
		)
	)
	(footprint ""
		(layer "F.Cu")
		(at 52.223162 -147.546822)
		(property "Reference" "R542"
			(at -2.1336 5.291582 0)
			(unlocked yes)
			(layer "F.SilkS")
			(effects
				(font
					(size 0.7874 0.5842)
					(thickness 0.1524)
				)
				(justify left)
			)
		)
		(property "Value" ""
			(at 0 0 0)
			(layer "F.Fab")
			(effects
				(font
					(size 1.27 1.27)
				)
			)
		)
		(duplicate_pad_numbers_are_jumpers no)
		(fp_line
			(start -0.7874 -0.406146)
			(end 0.7874 -0.406146)
			(stroke
				(width 0.1524)
				(type default)
			)
			(layer "F.SilkS")
		)
		(fp_line
			(start -0.7874 0.406146)
			(end -0.7874 -0.406146)
			(stroke
				(width 0.1524)
				(type default)
			)
			(layer "F.SilkS")
		)
		(fp_line
			(start 0.7874 -0.406146)
			(end 0.7874 0.406146)
			(stroke
				(width 0.1524)
				(type default)
			)
			(layer "F.SilkS")
		)
		(fp_line
			(start 0.7874 0.406146)
			(end -0.7874 0.406146)
			(stroke
				(width 0.1524)
				(type default)
			)
			(layer "F.SilkS")
		)
		(fp_poly
			(pts
				(xy -0.508 0.2794) (xy -0.508 0.2286) (xy -0.635 0.2286) (xy -0.635 -0.254) (xy -0.5334 -0.254)
				(xy -0.5334 -0.2794) (xy 0.5334 -0.2794) (xy 0.5334 -0.254) (xy 0.635 -0.254) (xy 0.635 0.254) (xy 0.5334 0.254)
				(xy 0.5334 0.2794)
			)
			(stroke
				(width 0)
				(type default)
			)
			(fill no)
			(layer "F.CrtYd")
		)
		(pad "1" smd rect
			(at 0.40005 0)
			(size 0.4572 0.508)
			(layers "F.Cu" "F.Mask" "F.Paste")
			(net "P3V3_NODE1")
		)
		(pad "2" smd rect
			(at -0.40005 0)
			(size 0.4572 0.508)
			(layers "F.Cu" "F.Mask" "F.Paste")
			(net "SPI_LAN1_NVM_CS_N")
		)
	)
	(footprint ""
		(layer "F.Cu")
		(at 157.530292 -26.594816 180)
		(property "Reference" "C532"
			(at -3.56108 -0.848106 90)
			(unlocked yes)
			(layer "F.SilkS")
			(effects
				(font
					(size 0.7874 0.5842)
					(thickness 0.1524)
				)
				(justify left)
			)
		)
		(property "Value" ""
			(at 0 0 180)
			(layer "F.Fab")
			(effects
				(font
					(size 1.27 1.27)
				)
			)
		)
		(duplicate_pad_numbers_are_jumpers no)
		(fp_line
			(start 0.7874 0.4064)
			(end -0.7874 0.4064)
			(stroke
				(width 0.1524)
				(type default)
			)
			(layer "F.SilkS")
		)
		(fp_line
			(start 0.7874 -0.4064)
			(end 0.7874 0.4064)
			(stroke
				(width 0.1524)
				(type default)
			)
			(layer "F.SilkS")
		)
		(fp_line
			(start 0 0.381)
			(end 0 -0.381)
			(stroke
				(width 0.1524)
				(type default)
			)
			(layer "F.SilkS")
		)
		(fp_line
			(start -0.7874 0.4064)
			(end -0.7874 -0.4064)
			(stroke
				(width 0.1524)
				(type default)
			)
			(layer "F.SilkS")
		)
		(fp_line
			(start -0.7874 -0.4064)
			(end 0.7874 -0.4064)
			(stroke
				(width 0.1524)
				(type default)
			)
			(layer "F.SilkS")
		)
		(fp_poly
			(pts
				(xy -0.5334 0.254) (xy -0.635 0.254) (xy -0.635 0.2286) (xy -0.635 -0.254) (xy -0.5334 -0.254) (xy -0.5334 -0.2794)
				(xy 0.5334 -0.2794) (xy 0.5334 -0.254) (xy 0.635 -0.254) (xy 0.635 0.254) (xy 0.5334 0.254) (xy 0.5334 0.2794)
				(xy -0.508 0.2794) (xy -0.5334 0.2794)
			)
			(stroke
				(width 0)
				(type default)
			)
			(fill no)
			(layer "F.CrtYd")
		)
		(pad "1" smd rect
			(at 0.40005 0 180)
			(size 0.4572 0.508)
			(layers "F.Cu" "F.Mask" "F.Paste")
			(net "GND")
		)
		(pad "2" smd rect
			(at -0.40005 0 180)
			(size 0.4572 0.508)
			(layers "F.Cu" "F.Mask" "F.Paste")
			(net "N21624894")
		)
	)
	(footprint ""
		(layer "F.Cu")
		(at 15.21206 -107.34802 -90)
		(property "Reference" "PC64"
			(at -7.638288 4.15798 0)
			(unlocked yes)
			(layer "F.SilkS")
			(effects
				(font
					(size 0.7874 0.5842)
					(thickness 0.1524)
				)
				(justify left)
			)
		)
		(property "Value" ""
			(at 0 0 270)
			(layer "F.Fab")
			(effects
				(font
					(size 1.27 1.27)
				)
			)
		)
		(duplicate_pad_numbers_are_jumpers no)
		(fp_line
			(start -2.249932 4.533392)
			(end -2.249932 -4.533392)
			(stroke
				(width 0.1524)
				(type default)
			)
			(layer "F.SilkS")
		)
		(fp_line
			(start 2.249932 4.533392)
			(end -2.249932 4.533392)
			(stroke
				(width 0.1524)
				(type default)
			)
			(layer "F.SilkS")
		)
		(fp_line
			(start -2.249932 -4.533392)
			(end 2.249932 -4.533392)
			(stroke
				(width 0.1524)
				(type default)
			)
			(layer "F.SilkS")
		)
		(fp_line
			(start 2.249932 -4.533392)
			(end 2.249932 4.533392)
			(stroke
				(width 0.1524)
				(type default)
			)
			(layer "F.SilkS")
		)
		(fp_poly
			(pts
				(xy 2.326132 -4.533392) (xy 2.326132 -5.39242) (xy -2.326132 -5.39242) (xy -2.326132 -4.533392)
			)
			(stroke
				(width 0)
				(type default)
			)
			(fill yes)
			(layer "F.SilkS")
		)
		(fp_poly
			(pts
				(xy -1.4605 4.457192) (xy -1.4605 3.750056) (xy -2.249932 3.750056) (xy -2.249932 -3.750056) (xy -1.4605 -3.750056)
				(xy -1.4605 -4.457192) (xy 1.4605 -4.457192) (xy 1.4605 -3.750056) (xy 2.249932 -3.750056) (xy 2.249932 3.750056)
				(xy 1.4605 3.750056) (xy 1.4605 4.457192)
			)
			(stroke
				(width 0)
				(type default)
			)
			(fill no)
			(layer "F.CrtYd")
		)
		(fp_line
			(start -2.249932 3.750056)
			(end -2.249932 -3.750056)
			(stroke
				(width 0.1)
				(type default)
			)
			(layer "F.Fab")
		)
		(fp_line
			(start 2.249932 3.750056)
			(end -2.249932 3.750056)
			(stroke
				(width 0.1)
				(type default)
			)
			(layer "F.Fab")
		)
		(fp_line
			(start -2.249932 -3.750056)
			(end 2.249932 -3.750056)
			(stroke
				(width 0.1)
				(type default)
			)
			(layer "F.Fab")
		)
		(fp_line
			(start 2.249932 -3.750056)
			(end 2.249932 3.750056)
			(stroke
				(width 0.1)
				(type default)
			)
			(layer "F.Fab")
		)
		(fp_text user "+"
			(at -6.83514 -6.076442 270)
			(unlocked yes)
			(layer "F.SilkS")
			(effects
				(font
					(size 1.27 0.9652)
					(thickness 0.1524)
				)
				(justify left)
			)
		)
		(fp_text user "+"
			(at -0.786384 -6.322314 270)
			(unlocked yes)
			(layer "F.Fab")
			(effects
				(font
					(size 1.905 1.4224)
					(thickness 0.000001)
				)
				(justify left)
			)
		)
		(pad "1" smd rect
			(at 0 -3.199892 180)
			(size 2.413 2.8194)
			(layers "F.Cu" "F.Mask" "F.Paste")
			(net "P1V05_NODE1")
		)
		(pad "2" smd rect
			(at 0 3.199892 180)
			(size 2.413 2.8194)
			(layers "F.Cu" "F.Mask" "F.Paste")
			(net "GND")
		)
	)
	(footprint ""
		(layer "F.Cu")
		(at 11.933174 -16.260572 -90)
		(property "Reference" "R652"
			(at 1.500124 6.319774 90)
			(unlocked yes)
			(layer "F.SilkS")
			(effects
				(font
					(size 0.7874 0.5842)
					(thickness 0.1524)
				)
				(justify left)
			)
		)
		(property "Value" ""
			(at 0 0 270)
			(layer "F.Fab")
			(effects
				(font
					(size 1.27 1.27)
				)
			)
		)
		(duplicate_pad_numbers_are_jumpers no)
		(fp_line
			(start -0.7874 0.4064)
			(end -0.7874 -0.4064)
			(stroke
				(width 0.1524)
				(type default)
			)
			(layer "F.SilkS")
		)
		(fp_line
			(start 0.7874 0.4064)
			(end -0.7874 0.4064)
			(stroke
				(width 0.1524)
				(type default)
			)
			(layer "F.SilkS")
		)
		(fp_line
			(start -0.7874 -0.4064)
			(end 0.7874 -0.4064)
			(stroke
				(width 0.1524)
				(type default)
			)
			(layer "F.SilkS")
		)
		(fp_line
			(start 0.7874 -0.4064)
			(end 0.7874 0.4064)
			(stroke
				(width 0.1524)
				(type default)
			)
			(layer "F.SilkS")
		)
		(fp_poly
			(pts
				(xy -0.508 0.2794) (xy -0.508 0.2286) (xy -0.635 0.2286) (xy -0.635 -0.254) (xy -0.5334 -0.254)
				(xy -0.5334 -0.2794) (xy 0.5334 -0.2794) (xy 0.5334 -0.254) (xy 0.635 -0.254) (xy 0.635 0.254) (xy 0.5334 0.254)
				(xy 0.5334 0.2794)
			)
			(stroke
				(width 0)
				(type default)
			)
			(fill no)
			(layer "F.CrtYd")
		)
		(pad "1" smd rect
			(at 0.40005 0 270)
			(size 0.4572 0.508)
			(layers "F.Cu" "F.Mask" "F.Paste")
			(net "P3V3_NODE1")
		)
		(pad "2" smd rect
			(at -0.40005 0 270)
			(size 0.4572 0.508)
			(layers "F.Cu" "F.Mask" "F.Paste")
			(net "N54251489")
		)
	)
	(footprint ""
		(layer "F.Cu")
		(at 100.496624 -131.539488 -90)
		(property "Reference" "PR45"
			(at 3.448812 2.178304 90)
			(unlocked yes)
			(layer "F.SilkS")
			(effects
				(font
					(size 0.7874 0.5842)
					(thickness 0.1524)
				)
				(justify left)
			)
		)
		(property "Value" ""
			(at 0 0 270)
			(layer "F.Fab")
			(effects
				(font
					(size 1.27 1.27)
				)
			)
		)
		(duplicate_pad_numbers_are_jumpers no)
		(fp_line
			(start -0.7874 0.4064)
			(end -0.7874 -0.4064)
			(stroke
				(width 0.1524)
				(type default)
			)
			(layer "F.SilkS")
		)
		(fp_line
			(start 0.7874 0.4064)
			(end -0.7874 0.4064)
			(stroke
				(width 0.1524)
				(type default)
			)
			(layer "F.SilkS")
		)
		(fp_line
			(start -0.7874 -0.4064)
			(end 0.7874 -0.4064)
			(stroke
				(width 0.1524)
				(type default)
			)
			(layer "F.SilkS")
		)
		(fp_line
			(start 0.7874 -0.4064)
			(end 0.7874 0.4064)
			(stroke
				(width 0.1524)
				(type default)
			)
			(layer "F.SilkS")
		)
		(fp_poly
			(pts
				(xy -0.508 0.2794) (xy -0.508 0.2286) (xy -0.635 0.2286) (xy -0.635 -0.254) (xy -0.5334 -0.254)
				(xy -0.5334 -0.2794) (xy 0.5334 -0.2794) (xy 0.5334 -0.254) (xy 0.635 -0.254) (xy 0.635 0.254) (xy 0.5334 0.254)
				(xy 0.5334 0.2794)
			)
			(stroke
				(width 0)
				(type default)
			)
			(fill no)
			(layer "F.CrtYd")
		)
		(pad "1" smd rect
			(at 0.40005 0 270)
			(size 0.4572 0.508)
			(layers "F.Cu" "F.Mask" "F.Paste")
			(net "P1V05_NODE1")
		)
		(pad "2" smd rect
			(at -0.40005 0 270)
			(size 0.4572 0.508)
			(layers "F.Cu" "F.Mask" "F.Paste")
			(net "SVID_CPU_NODE1_PVCCP_DAT")
		)
	)
	(footprint ""
		(layer "F.Cu")
		(at 184.7342 -174.4218 180)
		(property "Reference" "R1315"
			(at -10.0076 -17.45107 0)
			(unlocked yes)
			(layer "F.SilkS")
			(effects
				(font
					(size 0.7874 0.5842)
					(thickness 0.1524)
				)
				(justify left)
			)
		)
		(property "Value" ""
			(at 0 0 180)
			(layer "F.Fab")
			(effects
				(font
					(size 1.27 1.27)
				)
			)
		)
		(duplicate_pad_numbers_are_jumpers no)
		(fp_line
			(start 0.7874 0.4064)
			(end -0.7874 0.4064)
			(stroke
				(width 0.1524)
				(type default)
			)
			(layer "F.SilkS")
		)
		(fp_line
			(start 0.7874 -0.4064)
			(end 0.7874 0.4064)
			(stroke
				(width 0.1524)
				(type default)
			)
			(layer "F.SilkS")
		)
		(fp_line
			(start -0.7874 0.4064)
			(end -0.7874 -0.4064)
			(stroke
				(width 0.1524)
				(type default)
			)
			(layer "F.SilkS")
		)
		(fp_line
			(start -0.7874 -0.4064)
			(end 0.7874 -0.4064)
			(stroke
				(width 0.1524)
				(type default)
			)
			(layer "F.SilkS")
		)
		(fp_poly
			(pts
				(xy -0.508 0.2794) (xy -0.508 0.2286) (xy -0.635 0.2286) (xy -0.635 -0.254) (xy -0.5334 -0.254)
				(xy -0.5334 -0.2794) (xy 0.5334 -0.2794) (xy 0.5334 -0.254) (xy 0.635 -0.254) (xy 0.635 0.254) (xy 0.5334 0.254)
				(xy 0.5334 0.2794)
			)
			(stroke
				(width 0)
				(type default)
			)
			(fill no)
			(layer "F.CrtYd")
		)
		(pad "1" smd rect
			(at 0.40005 0 180)
			(size 0.4572 0.508)
			(layers "F.Cu" "F.Mask" "F.Paste")
			(net "POWER_SW2_PWR_CTR_12V")
		)
		(pad "2" smd rect
			(at -0.40005 0 180)
			(size 0.4572 0.508)
			(layers "F.Cu" "F.Mask" "F.Paste")
			(net "POWER_SW2_PWR_CTR_12V_R")
		)
	)
)
